(kicad_pcb
	(version 20260206)
	(generator "pcbnew")
	(generator_version "10.0")
	(general
		(thickness 1.6)
		(legacy_teardrops no)
	)
	(paper "A4")
	(title_block
		(title "03242023_DA0F0TMBIJ0_F0T_Motherboard_J_brd_V01_OCP.brd")
		(comment 1 "Grand Teton / footprints 841-845 of 6105")
	)
	(layers
		(0 "F.Cu" signal "TOP")
		(4 "In1.Cu" signal "GND")
		(6 "In2.Cu" signal "IN1")
		(8 "In3.Cu" signal "GND1")
		(10 "In4.Cu" signal "IN2")
		(12 "In5.Cu" signal "GND2")
		(14 "In6.Cu" signal "IN3")
		(16 "In7.Cu" signal "GND3")
		(18 "In8.Cu" signal "VCC")
		(20 "In9.Cu" signal "VCC1")
		(22 "In10.Cu" signal "GND4")
		(24 "In11.Cu" signal "IN4")
		(26 "In12.Cu" signal "GND5")
		(28 "In13.Cu" signal "IN5")
		(30 "In14.Cu" signal "GND6")
		(32 "In15.Cu" signal "IN6")
		(34 "In16.Cu" signal "GND7")
		(2 "B.Cu" signal "BOTTOM")
		(9 "F.Adhes" user "F.Adhesive")
		(11 "B.Adhes" user "B.Adhesive")
		(13 "F.Paste" user "Package Geometry/Pastemask Top")
		(15 "B.Paste" user "Package Geometry/Pastemask Bottom")
		(5 "F.SilkS" user "Ref Des/Silkscreen Top")
		(7 "B.SilkS" user "Ref Des/Silkscreen Bottom")
		(1 "F.Mask" user "Board Geometry/Soldermask Top")
		(3 "B.Mask" user "Board Geometry/Soldermask Bottom")
		(17 "Dwgs.User" user "User.Drawings")
		(19 "Cmts.User" user "User.Comments")
		(21 "Eco1.User" user "User.Eco1")
		(23 "Eco2.User" user "User.Eco2")
		(25 "Edge.Cuts" user "Board Geometry/Outline")
		(27 "Margin" user)
		(31 "F.CrtYd" user "Package Geometry/Place Bound Top")
		(29 "B.CrtYd" user "Package Geometry/Place Bound Bottom")
		(35 "F.Fab" user "Ref Des/Assembly Top")
		(33 "B.Fab" user "Ref Des/Assembly Bottom")
	)
	(footprint ""
		(layer "F.Cu")
		(at 114.706654 -358.93375)
		(property "Reference" "PC101"
			(at 0 0 0)
			(layer "F.SilkS")
			(hide yes)
			(effects
				(font
					(size 1.27 1.27)
				)
			)
		)
		(property "Value" ""
			(at 0 0 0)
			(layer "F.Fab")
			(effects
				(font
					(size 1.27 1.27)
				)
			)
		)
		(duplicate_pad_numbers_are_jumpers no)
		(fp_line
			(start -0.7874 -0.4064)
			(end 0.7874 -0.4064)
			(stroke
				(width 0.1524)
				(type default)
			)
			(layer "F.SilkS")
		)
		(fp_line
			(start -0.7874 0.4064)
			(end -0.7874 -0.4064)
			(stroke
				(width 0.1524)
				(type default)
			)
			(layer "F.SilkS")
		)
		(fp_line
			(start 0.7874 -0.4064)
			(end 0.7874 0.4064)
			(stroke
				(width 0.1524)
				(type default)
			)
			(layer "F.SilkS")
		)
		(fp_line
			(start 0.7874 0.4064)
			(end -0.7874 0.4064)
			(stroke
				(width 0.1524)
				(type default)
			)
			(layer "F.SilkS")
		)
		(fp_line
			(start -0.67945 -0.305054)
			(end -0.12065 -0.305054)
			(stroke
				(width 0.1)
				(type default)
			)
			(layer "F.Fab")
		)
		(fp_line
			(start -0.67945 0.3048)
			(end -0.67945 -0.305054)
			(stroke
				(width 0.1)
				(type default)
			)
			(layer "F.Fab")
		)
		(fp_line
			(start -0.12065 -0.305054)
			(end -0.12065 -0.2794)
			(stroke
				(width 0.1)
				(type default)
			)
			(layer "F.Fab")
		)
		(fp_line
			(start -0.12065 -0.2794)
			(end 0.12065 -0.2794)
			(stroke
				(width 0.1)
				(type default)
			)
			(layer "F.Fab")
		)
		(fp_line
			(start -0.12065 0.2794)
			(end -0.12065 0.3048)
			(stroke
				(width 0.1)
				(type default)
			)
			(layer "F.Fab")
		)
		(fp_line
			(start -0.12065 0.3048)
			(end -0.67945 0.3048)
			(stroke
				(width 0.1)
				(type default)
			)
			(layer "F.Fab")
		)
		(fp_line
			(start 0.120396 0.2794)
			(end -0.12065 0.2794)
			(stroke
				(width 0.1)
				(type default)
			)
			(layer "F.Fab")
		)
		(fp_line
			(start 0.120396 0.3048)
			(end 0.120396 0.2794)
			(stroke
				(width 0.1)
				(type default)
			)
			(layer "F.Fab")
		)
		(fp_line
			(start 0.12065 -0.3048)
			(end 0.67945 -0.3048)
			(stroke
				(width 0.1)
				(type default)
			)
			(layer "F.Fab")
		)
		(fp_line
			(start 0.12065 -0.2794)
			(end 0.12065 -0.3048)
			(stroke
				(width 0.1)
				(type default)
			)
			(layer "F.Fab")
		)
		(fp_line
			(start 0.67945 -0.3048)
			(end 0.67945 0.3048)
			(stroke
				(width 0.1)
				(type default)
			)
			(layer "F.Fab")
		)
		(fp_line
			(start 0.67945 0.3048)
			(end 0.120396 0.3048)
			(stroke
				(width 0.1)
				(type default)
			)
			(layer "F.Fab")
		)
		(pad "1" smd circle
			(at -0.40005 0)
			(size 0 0)
			(layers "F.Cu" "F.Mask" "F.Paste")
			(net "PVCCFA_EHV_FIVRA_CPU1_BTSEN")
		)
		(pad "2" smd circle
			(at 0.40005 0)
			(size 0 0)
			(layers "F.Cu" "F.Mask" "F.Paste")
			(net "GND")
		)
	)
	(footprint ""
		(layer "F.Cu")
		(at 377.46559 -64.866012 180)
		(property "Reference" "R751"
			(at 0 0 180)
			(layer "F.SilkS")
			(hide yes)
			(effects
				(font
					(size 1.27 1.27)
				)
			)
		)
		(property "Value" ""
			(at 0 0 180)
			(layer "F.Fab")
			(effects
				(font
					(size 1.27 1.27)
				)
			)
		)
		(duplicate_pad_numbers_are_jumpers no)
		(fp_line
			(start 0.7874 0.4064)
			(end -0.7874 0.4064)
			(stroke
				(width 0.1524)
				(type default)
			)
			(layer "F.SilkS")
		)
		(fp_line
			(start 0.7874 -0.4064)
			(end 0.7874 0.4064)
			(stroke
				(width 0.1524)
				(type default)
			)
			(layer "F.SilkS")
		)
		(fp_line
			(start -0.7874 0.4064)
			(end -0.7874 -0.4064)
			(stroke
				(width 0.1524)
				(type default)
			)
			(layer "F.SilkS")
		)
		(fp_line
			(start -0.7874 -0.4064)
			(end 0.7874 -0.4064)
			(stroke
				(width 0.1524)
				(type default)
			)
			(layer "F.SilkS")
		)
		(fp_line
			(start 0.67945 0.3048)
			(end 0.120396 0.3048)
			(stroke
				(width 0.1)
				(type default)
			)
			(layer "F.Fab")
		)
		(fp_line
			(start 0.67945 -0.3048)
			(end 0.67945 0.3048)
			(stroke
				(width 0.1)
				(type default)
			)
			(layer "F.Fab")
		)
		(fp_line
			(start 0.12065 -0.2794)
			(end 0.12065 -0.3048)
			(stroke
				(width 0.1)
				(type default)
			)
			(layer "F.Fab")
		)
		(fp_line
			(start 0.12065 -0.3048)
			(end 0.67945 -0.3048)
			(stroke
				(width 0.1)
				(type default)
			)
			(layer "F.Fab")
		)
		(fp_line
			(start 0.120396 0.3048)
			(end 0.120396 0.2794)
			(stroke
				(width 0.1)
				(type default)
			)
			(layer "F.Fab")
		)
		(fp_line
			(start 0.120396 0.2794)
			(end -0.12065 0.2794)
			(stroke
				(width 0.1)
				(type default)
			)
			(layer "F.Fab")
		)
		(fp_line
			(start -0.12065 0.3048)
			(end -0.67945 0.3048)
			(stroke
				(width 0.1)
				(type default)
			)
			(layer "F.Fab")
		)
		(fp_line
			(start -0.12065 0.2794)
			(end -0.12065 0.3048)
			(stroke
				(width 0.1)
				(type default)
			)
			(layer "F.Fab")
		)
		(fp_line
			(start -0.12065 -0.2794)
			(end 0.12065 -0.2794)
			(stroke
				(width 0.1)
				(type default)
			)
			(layer "F.Fab")
		)
		(fp_line
			(start -0.12065 -0.305054)
			(end -0.12065 -0.2794)
			(stroke
				(width 0.1)
				(type default)
			)
			(layer "F.Fab")
		)
		(fp_line
			(start -0.67945 0.3048)
			(end -0.67945 -0.305054)
			(stroke
				(width 0.1)
				(type default)
			)
			(layer "F.Fab")
		)
		(fp_line
			(start -0.67945 -0.305054)
			(end -0.12065 -0.305054)
			(stroke
				(width 0.1)
				(type default)
			)
			(layer "F.Fab")
		)
		(pad "1" smd circle
			(at -0.40005 0 180)
			(size 0 0)
			(layers "F.Cu" "F.Mask" "F.Paste")
			(net "P1V05_PCH_AUX")
		)
		(pad "2" smd circle
			(at 0.40005 0 180)
			(size 0 0)
			(layers "F.Cu" "F.Mask" "F.Paste")
			(net "H_DBP_PRDY_N_PCH")
		)
	)
	(footprint ""
		(layer "F.Cu")
		(at 495.90833 -153.174192 -90)
		(property "Reference" "X4"
			(at -1.336548 2.921 90)
			(unlocked yes)
			(layer "F.SilkS")
			(effects
				(font
					(size 0.7874 0.5842)
					(thickness 0.1524)
				)
				(justify left)
			)
		)
		(property "Value" ""
			(at 0 0 270)
			(layer "F.Fab")
			(effects
				(font
					(size 1.27 1.27)
				)
			)
		)
		(property "Device Type" "TP_TDR_4P_FTS_TH-TP_TDR_4P_DIPA"
			(at 1.30175 1.27 0)
			(unlocked yes)
			(layer "F.Fab")
			(hide yes)
			(effects
				(font
					(size 0.635 0.4064)
					(thickness 0.1524)
				)
			)
		)
		(property "User Part Number" "N_A"
			(at 1.30175 1.27 0)
			(unlocked yes)
			(layer "Cmts.User")
			(hide yes)
			(effects
				(font
					(size 0.635 0.4064)
					(thickness 0.1524)
				)
			)
		)
		(duplicate_pad_numbers_are_jumpers no)
		(fp_line
			(start 0 3.81)
			(end 2.54 3.81)
			(stroke
				(width 0.1524)
				(type default)
			)
			(layer "F.SilkS")
		)
		(fp_line
			(start 2.54 3.81)
			(end 2.54 3.6703)
			(stroke
				(width 0.1524)
				(type default)
			)
			(layer "F.SilkS")
		)
		(fp_line
			(start 0 3.175)
			(end 0 3.81)
			(stroke
				(width 0.1524)
				(type default)
			)
			(layer "F.SilkS")
		)
		(fp_line
			(start 2.54 1.4097)
			(end 2.54 1.1303)
			(stroke
				(width 0.1524)
				(type default)
			)
			(layer "F.SilkS")
		)
		(fp_line
			(start 0 0.635)
			(end 0 1.905)
			(stroke
				(width 0.1524)
				(type default)
			)
			(layer "F.SilkS")
		)
		(fp_line
			(start 2.54 -1.1303)
			(end 2.54 -1.27)
			(stroke
				(width 0.1524)
				(type default)
			)
			(layer "F.SilkS")
		)
		(fp_line
			(start 0 -1.27)
			(end 0 -0.635)
			(stroke
				(width 0.1524)
				(type default)
			)
			(layer "F.SilkS")
		)
		(fp_line
			(start 2.54 -1.27)
			(end 0 -1.27)
			(stroke
				(width 0.1524)
				(type default)
			)
			(layer "F.SilkS")
		)
		(fp_poly
			(pts
				(xy -0.761746 0) (xy -2.285746 0.762) (xy -2.285746 -0.762)
			)
			(stroke
				(width 0)
				(type default)
			)
			(fill yes)
			(layer "F.SilkS")
		)
		(fp_line
			(start 0 3.81)
			(end 2.54 3.81)
			(stroke
				(width 0.1)
				(type default)
			)
			(layer "F.Fab")
		)
		(fp_line
			(start 2.54 3.81)
			(end 2.54 -1.27)
			(stroke
				(width 0.1)
				(type default)
			)
			(layer "F.Fab")
		)
		(fp_line
			(start 0 -1.27)
			(end 0 3.81)
			(stroke
				(width 0.1)
				(type default)
			)
			(layer "F.Fab")
		)
		(fp_line
			(start 2.54 -1.27)
			(end 0 -1.27)
			(stroke
				(width 0.1)
				(type default)
			)
			(layer "F.Fab")
		)
		(fp_poly
			(pts
				(xy -0.761746 0) (xy -2.285746 -0.762) (xy -2.285746 0.762)
			)
			(stroke
				(width 0)
				(type default)
			)
			(fill yes)
			(layer "F.Fab")
		)
		(pad "1" thru_hole circle
			(at 0 0 270)
			(size 1.0033 1.0033)
			(drill 0.249936)
			(layers "*.Cu" "*.Mask")
			(remove_unused_layers no)
			(net "TDR_DIFF_85_IN3_DP")
			(clearance 0.10795)
			(thermal_gap 0.10795)
			(padstack
				(mode front_inner_back)
				(layer "Inner"
					(shape circle)
					(size 0.8001 0.8001)
					(clearance 0.1524)
				)
				(layer "B.Cu"
					(shape circle)
					(size 1.0033 1.0033)
					(clearance 0.10795)
				)
			)
		)
		(pad "2" thru_hole circle
			(at 2.54 0 270)
			(size 1.9939 1.9939)
			(drill 0.249936)
			(layers "*.Cu" "*.Mask")
			(remove_unused_layers no)
			(net "T1_GND")
			(clearance 0.10795)
			(thermal_gap 0.10795)
			(padstack
				(mode front_inner_back)
				(layer "Inner"
					(shape circle)
					(size 0.8001 0.8001)
					(clearance 0.1524)
				)
				(layer "B.Cu"
					(shape circle)
					(size 1.9939 1.9939)
					(clearance 0.10795)
				)
			)
		)
		(pad "3" thru_hole circle
			(at 2.54 2.54 270)
			(size 1.9939 1.9939)
			(drill 0.249936)
			(layers "*.Cu" "*.Mask")
			(remove_unused_layers no)
			(net "T1_GND")
			(clearance 0.10795)
			(thermal_gap 0.10795)
			(padstack
				(mode front_inner_back)
				(layer "Inner"
					(shape circle)
					(size 0.8001 0.8001)
					(clearance 0.1524)
				)
				(layer "B.Cu"
					(shape circle)
					(size 1.9939 1.9939)
					(clearance 0.10795)
				)
			)
		)
		(pad "4" thru_hole circle
			(at 0 2.54 270)
			(size 1.0033 1.0033)
			(drill 0.249936)
			(layers "*.Cu" "*.Mask")
			(remove_unused_layers no)
			(net "TDR_DIFF_85_IN3_DN")
			(clearance 0.10795)
			(thermal_gap 0.10795)
			(padstack
				(mode front_inner_back)
				(layer "Inner"
					(shape circle)
					(size 0.8001 0.8001)
					(clearance 0.1524)
				)
				(layer "B.Cu"
					(shape circle)
					(size 1.0033 1.0033)
					(clearance 0.10795)
				)
			)
		)
	)
	(footprint ""
		(layer "F.Cu")
		(at 149.898608 -73.285858 180)
		(property "Reference" "C1613"
			(at 0 0 180)
			(layer "F.SilkS")
			(hide yes)
			(effects
				(font
					(size 1.27 1.27)
				)
			)
		)
		(property "Value" ""
			(at 0 0 180)
			(layer "F.Fab")
			(effects
				(font
					(size 1.27 1.27)
				)
			)
		)
		(duplicate_pad_numbers_are_jumpers no)
		(fp_line
			(start 0.7874 0.4064)
			(end -0.7874 0.4064)
			(stroke
				(width 0.1524)
				(type default)
			)
			(layer "F.SilkS")
		)
		(fp_line
			(start 0.7874 -0.4064)
			(end 0.7874 0.4064)
			(stroke
				(width 0.1524)
				(type default)
			)
			(layer "F.SilkS")
		)
		(fp_line
			(start -0.7874 0.4064)
			(end -0.7874 -0.4064)
			(stroke
				(width 0.1524)
				(type default)
			)
			(layer "F.SilkS")
		)
		(fp_line
			(start -0.7874 -0.4064)
			(end 0.7874 -0.4064)
			(stroke
				(width 0.1524)
				(type default)
			)
			(layer "F.SilkS")
		)
		(fp_line
			(start 0.67945 0.3048)
			(end 0.120396 0.3048)
			(stroke
				(width 0.1)
				(type default)
			)
			(layer "F.Fab")
		)
		(fp_line
			(start 0.67945 -0.3048)
			(end 0.67945 0.3048)
			(stroke
				(width 0.1)
				(type default)
			)
			(layer "F.Fab")
		)
		(fp_line
			(start 0.12065 -0.2794)
			(end 0.12065 -0.3048)
			(stroke
				(width 0.1)
				(type default)
			)
			(layer "F.Fab")
		)
		(fp_line
			(start 0.12065 -0.3048)
			(end 0.67945 -0.3048)
			(stroke
				(width 0.1)
				(type default)
			)
			(layer "F.Fab")
		)
		(fp_line
			(start 0.120396 0.3048)
			(end 0.120396 0.2794)
			(stroke
				(width 0.1)
				(type default)
			)
			(layer "F.Fab")
		)
		(fp_line
			(start 0.120396 0.2794)
			(end -0.12065 0.2794)
			(stroke
				(width 0.1)
				(type default)
			)
			(layer "F.Fab")
		)
		(fp_line
			(start -0.12065 0.3048)
			(end -0.67945 0.3048)
			(stroke
				(width 0.1)
				(type default)
			)
			(layer "F.Fab")
		)
		(fp_line
			(start -0.12065 0.2794)
			(end -0.12065 0.3048)
			(stroke
				(width 0.1)
				(type default)
			)
			(layer "F.Fab")
		)
		(fp_line
			(start -0.12065 -0.2794)
			(end 0.12065 -0.2794)
			(stroke
				(width 0.1)
				(type default)
			)
			(layer "F.Fab")
		)
		(fp_line
			(start -0.12065 -0.305054)
			(end -0.12065 -0.2794)
			(stroke
				(width 0.1)
				(type default)
			)
			(layer "F.Fab")
		)
		(fp_line
			(start -0.67945 0.3048)
			(end -0.67945 -0.305054)
			(stroke
				(width 0.1)
				(type default)
			)
			(layer "F.Fab")
		)
		(fp_line
			(start -0.67945 -0.305054)
			(end -0.12065 -0.305054)
			(stroke
				(width 0.1)
				(type default)
			)
			(layer "F.Fab")
		)
		(pad "1" smd circle
			(at -0.40005 0 180)
			(size 0 0)
			(layers "F.Cu" "F.Mask" "F.Paste")
			(net "P3V3_AUX")
		)
		(pad "2" smd circle
			(at 0.40005 0 180)
			(size 0 0)
			(layers "F.Cu" "F.Mask" "F.Paste")
			(net "GND")
		)
	)
	(footprint ""
		(layer "F.Cu")
		(at 306.83454 -433.0573 90)
		(property "Reference" "R4142"
			(at 0 0 90)
			(layer "F.SilkS")
			(hide yes)
			(effects
				(font
					(size 1.27 1.27)
				)
			)
		)
		(property "Value" ""
			(at 0 0 90)
			(layer "F.Fab")
			(effects
				(font
					(size 1.27 1.27)
				)
			)
		)
		(duplicate_pad_numbers_are_jumpers no)
		(fp_line
			(start 0.7874 -0.4064)
			(end 0.7874 0.4064)
			(stroke
				(width 0.1524)
				(type default)
			)
			(layer "F.SilkS")
		)
		(fp_line
			(start -0.7874 -0.4064)
			(end 0.7874 -0.4064)
			(stroke
				(width 0.1524)
				(type default)
			)
			(layer "F.SilkS")
		)
		(fp_line
			(start 0.7874 0.4064)
			(end -0.7874 0.4064)
			(stroke
				(width 0.1524)
				(type default)
			)
			(layer "F.SilkS")
		)
		(fp_line
			(start -0.7874 0.4064)
			(end -0.7874 -0.4064)
			(stroke
				(width 0.1524)
				(type default)
			)
			(layer "F.SilkS")
		)
		(fp_line
			(start -0.12065 -0.305054)
			(end -0.12065 -0.2794)
			(stroke
				(width 0.1)
				(type default)
			)
			(layer "F.Fab")
		)
		(fp_line
			(start -0.67945 -0.305054)
			(end -0.12065 -0.305054)
			(stroke
				(width 0.1)
				(type default)
			)
			(layer "F.Fab")
		)
		(fp_line
			(start 0.67945 -0.3048)
			(end 0.67945 0.3048)
			(stroke
				(width 0.1)
				(type default)
			)
			(layer "F.Fab")
		)
		(fp_line
			(start 0.12065 -0.3048)
			(end 0.67945 -0.3048)
			(stroke
				(width 0.1)
				(type default)
			)
			(layer "F.Fab")
		)
		(fp_line
			(start 0.12065 -0.2794)
			(end 0.12065 -0.3048)
			(stroke
				(width 0.1)
				(type default)
			)
			(layer "F.Fab")
		)
		(fp_line
			(start -0.12065 -0.2794)
			(end 0.12065 -0.2794)
			(stroke
				(width 0.1)
				(type default)
			)
			(layer "F.Fab")
		)
		(fp_line
			(start 0.120396 0.2794)
			(end -0.12065 0.2794)
			(stroke
				(width 0.1)
				(type default)
			)
			(layer "F.Fab")
		)
		(fp_line
			(start -0.12065 0.2794)
			(end -0.12065 0.3048)
			(stroke
				(width 0.1)
				(type default)
			)
			(layer "F.Fab")
		)
		(fp_line
			(start 0.67945 0.3048)
			(end 0.120396 0.3048)
			(stroke
				(width 0.1)
				(type default)
			)
			(layer "F.Fab")
		)
		(fp_line
			(start 0.120396 0.3048)
			(end 0.120396 0.2794)
			(stroke
				(width 0.1)
				(type default)
			)
			(layer "F.Fab")
		)
		(fp_line
			(start -0.12065 0.3048)
			(end -0.67945 0.3048)
			(stroke
				(width 0.1)
				(type default)
			)
			(layer "F.Fab")
		)
		(fp_line
			(start -0.67945 0.3048)
			(end -0.67945 -0.305054)
			(stroke
				(width 0.1)
				(type default)
			)
			(layer "F.Fab")
		)
		(pad "1" smd circle
			(at -0.40005 0 90)
			(size 0 0)
			(layers "F.Cu" "F.Mask" "F.Paste")
			(net "P3V3_AUX")
		)
		(pad "2" smd circle
			(at 0.40005 0 90)
			(size 0 0)
			(layers "F.Cu" "F.Mask" "F.Paste")
			(net "PRSNT_CABLE_GPU_A2_ISO_N")
		)
	)
)
